(kicad_pcb
	(version 20260206)
	(generator "pcbnew")
	(generator_version "10.0")
	(general
		(thickness 1.6)
		(legacy_teardrops no)
	)
	(paper "A4")
	(title_block
		(title "12092022_DA0F0TFB6D0_F0T_FAN_BOARD_MP5048_D_brd_v02_OCP.brd")
		(comment 1 "Grand Teton / footprints 334-339 of 924")
	)
	(layers
		(0 "F.Cu" signal "TOP")
		(4 "In1.Cu" signal "GND")
		(6 "In2.Cu" signal "IN1")
		(8 "In3.Cu" signal "IN2")
		(10 "In4.Cu" signal "GND1")
		(2 "B.Cu" signal "BOTTOM")
		(9 "F.Adhes" user "F.Adhesive")
		(11 "B.Adhes" user "B.Adhesive")
		(13 "F.Paste" user "Package Geometry/Pastemask Top")
		(15 "B.Paste" user "Package Geometry/Pastemask Bottom")
		(5 "F.SilkS" user "Ref Des/Silkscreen Top")
		(7 "B.SilkS" user "Ref Des/Silkscreen Bottom")
		(1 "F.Mask" user "Board Geometry/Soldermask Top")
		(3 "B.Mask" user "Board Geometry/Soldermask Bottom")
		(17 "Dwgs.User" user "User.Drawings")
		(19 "Cmts.User" user "User.Comments")
		(21 "Eco1.User" user "User.Eco1")
		(23 "Eco2.User" user "User.Eco2")
		(25 "Edge.Cuts" user "Board Geometry/Outline")
		(27 "Margin" user)
		(31 "F.CrtYd" user "Package Geometry/Place Bound Top")
		(29 "B.CrtYd" user "Package Geometry/Place Bound Bottom")
		(35 "F.Fab" user "Ref Des/Assembly Top")
		(33 "B.Fab" user "Ref Des/Assembly Bottom")
	)
	(footprint ""
		(layer "F.Cu")
		(at 19.431 -17.526 90)
		(property "Reference" "C2016"
			(at 0 0 90)
			(layer "F.SilkS")
			(hide yes)
			(effects
				(font
					(size 1.27 1.27)
				)
			)
		)
		(property "Value" ""
			(at 0 0 90)
			(layer "F.Fab")
			(effects
				(font
					(size 1.27 1.27)
				)
			)
		)
		(duplicate_pad_numbers_are_jumpers no)
		(fp_line
			(start 0.7874 -0.4064)
			(end 0.7874 0.4064)
			(stroke
				(width 0.1524)
				(type default)
			)
			(layer "F.SilkS")
		)
		(fp_line
			(start -0.7874 -0.4064)
			(end 0.7874 -0.4064)
			(stroke
				(width 0.1524)
				(type default)
			)
			(layer "F.SilkS")
		)
		(fp_line
			(start 0.7874 0.4064)
			(end -0.7874 0.4064)
			(stroke
				(width 0.1524)
				(type default)
			)
			(layer "F.SilkS")
		)
		(fp_line
			(start -0.7874 0.4064)
			(end -0.7874 -0.4064)
			(stroke
				(width 0.1524)
				(type default)
			)
			(layer "F.SilkS")
		)
		(fp_line
			(start -0.12065 -0.305054)
			(end -0.12065 -0.2794)
			(stroke
				(width 0.1)
				(type default)
			)
			(layer "F.Fab")
		)
		(fp_line
			(start -0.67945 -0.305054)
			(end -0.12065 -0.305054)
			(stroke
				(width 0.1)
				(type default)
			)
			(layer "F.Fab")
		)
		(fp_line
			(start 0.67945 -0.3048)
			(end 0.67945 0.3048)
			(stroke
				(width 0.1)
				(type default)
			)
			(layer "F.Fab")
		)
		(fp_line
			(start 0.12065 -0.3048)
			(end 0.67945 -0.3048)
			(stroke
				(width 0.1)
				(type default)
			)
			(layer "F.Fab")
		)
		(fp_line
			(start 0.12065 -0.2794)
			(end 0.12065 -0.3048)
			(stroke
				(width 0.1)
				(type default)
			)
			(layer "F.Fab")
		)
		(fp_line
			(start -0.12065 -0.2794)
			(end 0.12065 -0.2794)
			(stroke
				(width 0.1)
				(type default)
			)
			(layer "F.Fab")
		)
		(fp_line
			(start 0.120396 0.2794)
			(end -0.12065 0.2794)
			(stroke
				(width 0.1)
				(type default)
			)
			(layer "F.Fab")
		)
		(fp_line
			(start -0.12065 0.2794)
			(end -0.12065 0.3048)
			(stroke
				(width 0.1)
				(type default)
			)
			(layer "F.Fab")
		)
		(fp_line
			(start 0.67945 0.3048)
			(end 0.120396 0.3048)
			(stroke
				(width 0.1)
				(type default)
			)
			(layer "F.Fab")
		)
		(fp_line
			(start 0.120396 0.3048)
			(end 0.120396 0.2794)
			(stroke
				(width 0.1)
				(type default)
			)
			(layer "F.Fab")
		)
		(fp_line
			(start -0.12065 0.3048)
			(end -0.67945 0.3048)
			(stroke
				(width 0.1)
				(type default)
			)
			(layer "F.Fab")
		)
		(fp_line
			(start -0.67945 0.3048)
			(end -0.67945 -0.305054)
			(stroke
				(width 0.1)
				(type default)
			)
			(layer "F.Fab")
		)
		(pad "1" smd circle
			(at -0.40005 0 90)
			(size 0 0)
			(layers "F.Cu" "F.Mask" "F.Paste")
			(net "FAN_4_TACH_IL_R")
		)
		(pad "2" smd circle
			(at 0.40005 0 90)
			(size 0 0)
			(layers "F.Cu" "F.Mask" "F.Paste")
			(net "GND")
		)
	)
	(footprint ""
		(layer "F.Cu")
		(at 34.417 -124.206 -90)
		(property "Reference" "R4937"
			(at 0 0 270)
			(layer "F.SilkS")
			(hide yes)
			(effects
				(font
					(size 1.27 1.27)
				)
			)
		)
		(property "Value" ""
			(at 0 0 270)
			(layer "F.Fab")
			(effects
				(font
					(size 1.27 1.27)
				)
			)
		)
		(duplicate_pad_numbers_are_jumpers no)
		(fp_line
			(start -0.7874 0.4064)
			(end -0.7874 -0.4064)
			(stroke
				(width 0.1524)
				(type default)
			)
			(layer "F.SilkS")
		)
		(fp_line
			(start 0.7874 0.4064)
			(end -0.7874 0.4064)
			(stroke
				(width 0.1524)
				(type default)
			)
			(layer "F.SilkS")
		)
		(fp_line
			(start -0.7874 -0.4064)
			(end 0.7874 -0.4064)
			(stroke
				(width 0.1524)
				(type default)
			)
			(layer "F.SilkS")
		)
		(fp_line
			(start 0.7874 -0.4064)
			(end 0.7874 0.4064)
			(stroke
				(width 0.1524)
				(type default)
			)
			(layer "F.SilkS")
		)
		(fp_line
			(start -0.67945 0.3048)
			(end -0.67945 -0.305054)
			(stroke
				(width 0.1)
				(type default)
			)
			(layer "F.Fab")
		)
		(fp_line
			(start -0.12065 0.3048)
			(end -0.67945 0.3048)
			(stroke
				(width 0.1)
				(type default)
			)
			(layer "F.Fab")
		)
		(fp_line
			(start 0.120396 0.3048)
			(end 0.120396 0.2794)
			(stroke
				(width 0.1)
				(type default)
			)
			(layer "F.Fab")
		)
		(fp_line
			(start 0.67945 0.3048)
			(end 0.120396 0.3048)
			(stroke
				(width 0.1)
				(type default)
			)
			(layer "F.Fab")
		)
		(fp_line
			(start -0.12065 0.2794)
			(end -0.12065 0.3048)
			(stroke
				(width 0.1)
				(type default)
			)
			(layer "F.Fab")
		)
		(fp_line
			(start 0.120396 0.2794)
			(end -0.12065 0.2794)
			(stroke
				(width 0.1)
				(type default)
			)
			(layer "F.Fab")
		)
		(fp_line
			(start -0.12065 -0.2794)
			(end 0.12065 -0.2794)
			(stroke
				(width 0.1)
				(type default)
			)
			(layer "F.Fab")
		)
		(fp_line
			(start 0.12065 -0.2794)
			(end 0.12065 -0.3048)
			(stroke
				(width 0.1)
				(type default)
			)
			(layer "F.Fab")
		)
		(fp_line
			(start 0.12065 -0.3048)
			(end 0.67945 -0.3048)
			(stroke
				(width 0.1)
				(type default)
			)
			(layer "F.Fab")
		)
		(fp_line
			(start 0.67945 -0.3048)
			(end 0.67945 0.3048)
			(stroke
				(width 0.1)
				(type default)
			)
			(layer "F.Fab")
		)
		(fp_line
			(start -0.67945 -0.305054)
			(end -0.12065 -0.305054)
			(stroke
				(width 0.1)
				(type default)
			)
			(layer "F.Fab")
		)
		(fp_line
			(start -0.12065 -0.305054)
			(end -0.12065 -0.2794)
			(stroke
				(width 0.1)
				(type default)
			)
			(layer "F.Fab")
		)
		(pad "1" smd circle
			(at -0.40005 0 270)
			(size 0 0)
			(layers "F.Cu" "F.Mask" "F.Paste")
			(net "MAX31790_U317_WD_START")
		)
		(pad "2" smd circle
			(at 0.40005 0 270)
			(size 0 0)
			(layers "F.Cu" "F.Mask" "F.Paste")
			(net "P3V3_AUX")
		)
	)
	(footprint ""
		(layer "F.Cu")
		(at 36.322 -286.639)
		(property "Reference" "D265"
			(at 2.286 0.53467 0)
			(unlocked yes)
			(layer "F.SilkS")
			(effects
				(font
					(size 0.7874 0.5842)
					(thickness 0.1524)
				)
				(justify left)
			)
		)
		(property "Value" ""
			(at 0 0 0)
			(layer "F.Fab")
			(effects
				(font
					(size 1.27 1.27)
				)
			)
		)
		(duplicate_pad_numbers_are_jumpers no)
		(fp_line
			(start -0.854964 -0.450088)
			(end -0.854964 0.450088)
			(stroke
				(width 0.1524)
				(type default)
			)
			(layer "F.SilkS")
		)
		(fp_line
			(start -0.854964 0.450088)
			(end 0.925068 0.450088)
			(stroke
				(width 0.1524)
				(type default)
			)
			(layer "F.SilkS")
		)
		(fp_line
			(start 0.845058 0.4064)
			(end 0.845058 -0.381)
			(stroke
				(width 0.1524)
				(type default)
			)
			(layer "F.SilkS")
		)
		(fp_line
			(start 0.870458 -0.2794)
			(end 0.845058 0.4064)
			(stroke
				(width 0.1524)
				(type default)
			)
			(layer "F.SilkS")
		)
		(fp_line
			(start 0.94488 -0.450088)
			(end -0.854964 -0.450088)
			(stroke
				(width 0.1524)
				(type default)
			)
			(layer "F.SilkS")
		)
		(fp_line
			(start 0.94488 0.450088)
			(end 0.94488 -0.450088)
			(stroke
				(width 0.1524)
				(type default)
			)
			(layer "F.SilkS")
		)
		(fp_line
			(start -0.54991 -0.350012)
			(end -0.54991 0.350012)
			(stroke
				(width 0.1)
				(type default)
			)
			(layer "F.Fab")
		)
		(fp_line
			(start -0.54991 0.350012)
			(end 0.54991 0.350012)
			(stroke
				(width 0.1)
				(type default)
			)
			(layer "F.Fab")
		)
		(fp_line
			(start 0.54991 -0.350012)
			(end -0.54991 -0.350012)
			(stroke
				(width 0.1)
				(type default)
			)
			(layer "F.Fab")
		)
		(fp_line
			(start 0.54991 0.350012)
			(end 0.54991 -0.350012)
			(stroke
				(width 0.1)
				(type default)
			)
			(layer "F.Fab")
		)
		(fp_text user "+"
			(at -0.5334 0.90805 180)
			(unlocked yes)
			(layer "F.SilkS")
			(effects
				(font
					(size 1.905 1.4224)
					(thickness 0.1524)
				)
				(justify left)
			)
		)
		(fp_text user "-"
			(at 2.286 0.22225 180)
			(unlocked yes)
			(layer "F.SilkS")
			(effects
				(font
					(size 1.905 1.4224)
					(thickness 0.1524)
				)
				(justify left)
			)
		)
		(fp_text user "+"
			(at -0.808228 0.239014 180)
			(unlocked yes)
			(layer "F.Fab")
			(effects
				(font
					(size 1.905 1.4224)
					(thickness 0.1524)
				)
				(justify left)
			)
		)
		(fp_text user "-"
			(at 2.48539 0.239014 180)
			(unlocked yes)
			(layer "F.Fab")
			(effects
				(font
					(size 1.905 1.4224)
					(thickness 0.1524)
				)
				(justify left)
			)
		)
		(pad "A" smd rect
			(at -0.424942 0)
			(size 0.5588 0.6096)
			(layers "F.Cu" "F.Mask" "F.Paste")
			(net "GND")
		)
		(pad "C" smd rect
			(at 0.424942 0 180)
			(size 0.5588 0.6096)
			(layers "F.Cu" "F.Mask" "F.Paste")
			(net "FAN_0_TACH_OL_D")
		)
	)
	(footprint ""
		(layer "F.Cu")
		(at 37.846 -133.858 180)
		(property "Reference" "R5600"
			(at 0 0 180)
			(layer "F.SilkS")
			(hide yes)
			(effects
				(font
					(size 1.27 1.27)
				)
			)
		)
		(property "Value" ""
			(at 0 0 180)
			(layer "F.Fab")
			(effects
				(font
					(size 1.27 1.27)
				)
			)
		)
		(duplicate_pad_numbers_are_jumpers no)
		(fp_line
			(start 0.7874 0.4064)
			(end -0.7874 0.4064)
			(stroke
				(width 0.1524)
				(type default)
			)
			(layer "F.SilkS")
		)
		(fp_line
			(start 0.7874 -0.4064)
			(end 0.7874 0.4064)
			(stroke
				(width 0.1524)
				(type default)
			)
			(layer "F.SilkS")
		)
		(fp_line
			(start -0.7874 0.4064)
			(end -0.7874 -0.4064)
			(stroke
				(width 0.1524)
				(type default)
			)
			(layer "F.SilkS")
		)
		(fp_line
			(start -0.7874 -0.4064)
			(end 0.7874 -0.4064)
			(stroke
				(width 0.1524)
				(type default)
			)
			(layer "F.SilkS")
		)
		(fp_line
			(start 0.67945 0.3048)
			(end 0.120396 0.3048)
			(stroke
				(width 0.1)
				(type default)
			)
			(layer "F.Fab")
		)
		(fp_line
			(start 0.67945 -0.3048)
			(end 0.67945 0.3048)
			(stroke
				(width 0.1)
				(type default)
			)
			(layer "F.Fab")
		)
		(fp_line
			(start 0.12065 -0.2794)
			(end 0.12065 -0.3048)
			(stroke
				(width 0.1)
				(type default)
			)
			(layer "F.Fab")
		)
		(fp_line
			(start 0.12065 -0.3048)
			(end 0.67945 -0.3048)
			(stroke
				(width 0.1)
				(type default)
			)
			(layer "F.Fab")
		)
		(fp_line
			(start 0.120396 0.3048)
			(end 0.120396 0.2794)
			(stroke
				(width 0.1)
				(type default)
			)
			(layer "F.Fab")
		)
		(fp_line
			(start 0.120396 0.2794)
			(end -0.12065 0.2794)
			(stroke
				(width 0.1)
				(type default)
			)
			(layer "F.Fab")
		)
		(fp_line
			(start -0.12065 0.3048)
			(end -0.67945 0.3048)
			(stroke
				(width 0.1)
				(type default)
			)
			(layer "F.Fab")
		)
		(fp_line
			(start -0.12065 0.2794)
			(end -0.12065 0.3048)
			(stroke
				(width 0.1)
				(type default)
			)
			(layer "F.Fab")
		)
		(fp_line
			(start -0.12065 -0.2794)
			(end 0.12065 -0.2794)
			(stroke
				(width 0.1)
				(type default)
			)
			(layer "F.Fab")
		)
		(fp_line
			(start -0.12065 -0.305054)
			(end -0.12065 -0.2794)
			(stroke
				(width 0.1)
				(type default)
			)
			(layer "F.Fab")
		)
		(fp_line
			(start -0.67945 0.3048)
			(end -0.67945 -0.305054)
			(stroke
				(width 0.1)
				(type default)
			)
			(layer "F.Fab")
		)
		(fp_line
			(start -0.67945 -0.305054)
			(end -0.12065 -0.305054)
			(stroke
				(width 0.1)
				(type default)
			)
			(layer "F.Fab")
		)
		(pad "1" smd rect
			(at -0.40005 0)
			(size 0.4572 0.508)
			(layers "F.Cu" "F.Mask" "F.Paste")
			(net "FAN_0_TACH_OL")
		)
		(pad "2" smd rect
			(at 0.40005 0)
			(size 0.4572 0.508)
			(layers "F.Cu" "F.Mask" "F.Paste")
			(net "FAN_0_TACH_OL_R1")
		)
	)
	(footprint ""
		(layer "F.Cu")
		(at 14.07795 -122.047 180)
		(property "Reference" "R5585"
			(at 0 0 180)
			(layer "F.SilkS")
			(hide yes)
			(effects
				(font
					(size 1.27 1.27)
				)
			)
		)
		(property "Value" ""
			(at 0 0 180)
			(layer "F.Fab")
			(effects
				(font
					(size 1.27 1.27)
				)
			)
		)
		(duplicate_pad_numbers_are_jumpers no)
		(fp_line
			(start 0.7874 0.4064)
			(end -0.7874 0.4064)
			(stroke
				(width 0.1524)
				(type default)
			)
			(layer "F.SilkS")
		)
		(fp_line
			(start 0.7874 -0.4064)
			(end 0.7874 0.4064)
			(stroke
				(width 0.1524)
				(type default)
			)
			(layer "F.SilkS")
		)
		(fp_line
			(start -0.7874 0.4064)
			(end -0.7874 -0.4064)
			(stroke
				(width 0.1524)
				(type default)
			)
			(layer "F.SilkS")
		)
		(fp_line
			(start -0.7874 -0.4064)
			(end 0.7874 -0.4064)
			(stroke
				(width 0.1524)
				(type default)
			)
			(layer "F.SilkS")
		)
		(fp_line
			(start 0.67945 0.3048)
			(end 0.120396 0.3048)
			(stroke
				(width 0.1)
				(type default)
			)
			(layer "F.Fab")
		)
		(fp_line
			(start 0.67945 -0.3048)
			(end 0.67945 0.3048)
			(stroke
				(width 0.1)
				(type default)
			)
			(layer "F.Fab")
		)
		(fp_line
			(start 0.12065 -0.2794)
			(end 0.12065 -0.3048)
			(stroke
				(width 0.1)
				(type default)
			)
			(layer "F.Fab")
		)
		(fp_line
			(start 0.12065 -0.3048)
			(end 0.67945 -0.3048)
			(stroke
				(width 0.1)
				(type default)
			)
			(layer "F.Fab")
		)
		(fp_line
			(start 0.120396 0.3048)
			(end 0.120396 0.2794)
			(stroke
				(width 0.1)
				(type default)
			)
			(layer "F.Fab")
		)
		(fp_line
			(start 0.120396 0.2794)
			(end -0.12065 0.2794)
			(stroke
				(width 0.1)
				(type default)
			)
			(layer "F.Fab")
		)
		(fp_line
			(start -0.12065 0.3048)
			(end -0.67945 0.3048)
			(stroke
				(width 0.1)
				(type default)
			)
			(layer "F.Fab")
		)
		(fp_line
			(start -0.12065 0.2794)
			(end -0.12065 0.3048)
			(stroke
				(width 0.1)
				(type default)
			)
			(layer "F.Fab")
		)
		(fp_line
			(start -0.12065 -0.2794)
			(end 0.12065 -0.2794)
			(stroke
				(width 0.1)
				(type default)
			)
			(layer "F.Fab")
		)
		(fp_line
			(start -0.12065 -0.305054)
			(end -0.12065 -0.2794)
			(stroke
				(width 0.1)
				(type default)
			)
			(layer "F.Fab")
		)
		(fp_line
			(start -0.67945 0.3048)
			(end -0.67945 -0.305054)
			(stroke
				(width 0.1)
				(type default)
			)
			(layer "F.Fab")
		)
		(fp_line
			(start -0.67945 -0.305054)
			(end -0.12065 -0.305054)
			(stroke
				(width 0.1)
				(type default)
			)
			(layer "F.Fab")
		)
		(pad "1" smd rect
			(at -0.40005 0)
			(size 0.4572 0.508)
			(layers "F.Cu" "F.Mask" "F.Paste")
			(net "FAN_4_PWM")
		)
		(pad "2" smd rect
			(at 0.40005 0)
			(size 0.4572 0.508)
			(layers "F.Cu" "F.Mask" "F.Paste")
			(net "FAN_4_PWM_R2")
		)
	)
	(footprint ""
		(layer "F.Cu")
		(at 31.623 -141.351 -90)
		(property "Reference" "R5280"
			(at 0 0 270)
			(layer "F.SilkS")
			(hide yes)
			(effects
				(font
					(size 1.27 1.27)
				)
			)
		)
		(property "Value" ""
			(at 0 0 270)
			(layer "F.Fab")
			(effects
				(font
					(size 1.27 1.27)
				)
			)
		)
		(duplicate_pad_numbers_are_jumpers no)
		(fp_line
			(start -0.7874 0.4064)
			(end -0.7874 -0.4064)
			(stroke
				(width 0.1524)
				(type default)
			)
			(layer "F.SilkS")
		)
		(fp_line
			(start 0.7874 0.4064)
			(end -0.7874 0.4064)
			(stroke
				(width 0.1524)
				(type default)
			)
			(layer "F.SilkS")
		)
		(fp_line
			(start -0.7874 -0.4064)
			(end 0.7874 -0.4064)
			(stroke
				(width 0.1524)
				(type default)
			)
			(layer "F.SilkS")
		)
		(fp_line
			(start 0.7874 -0.4064)
			(end 0.7874 0.4064)
			(stroke
				(width 0.1524)
				(type default)
			)
			(layer "F.SilkS")
		)
		(fp_line
			(start -0.67945 0.3048)
			(end -0.67945 -0.305054)
			(stroke
				(width 0.1)
				(type default)
			)
			(layer "F.Fab")
		)
		(fp_line
			(start -0.12065 0.3048)
			(end -0.67945 0.3048)
			(stroke
				(width 0.1)
				(type default)
			)
			(layer "F.Fab")
		)
		(fp_line
			(start 0.120396 0.3048)
			(end 0.120396 0.2794)
			(stroke
				(width 0.1)
				(type default)
			)
			(layer "F.Fab")
		)
		(fp_line
			(start 0.67945 0.3048)
			(end 0.120396 0.3048)
			(stroke
				(width 0.1)
				(type default)
			)
			(layer "F.Fab")
		)
		(fp_line
			(start -0.12065 0.2794)
			(end -0.12065 0.3048)
			(stroke
				(width 0.1)
				(type default)
			)
			(layer "F.Fab")
		)
		(fp_line
			(start 0.120396 0.2794)
			(end -0.12065 0.2794)
			(stroke
				(width 0.1)
				(type default)
			)
			(layer "F.Fab")
		)
		(fp_line
			(start -0.12065 -0.2794)
			(end 0.12065 -0.2794)
			(stroke
				(width 0.1)
				(type default)
			)
			(layer "F.Fab")
		)
		(fp_line
			(start 0.12065 -0.2794)
			(end 0.12065 -0.3048)
			(stroke
				(width 0.1)
				(type default)
			)
			(layer "F.Fab")
		)
		(fp_line
			(start 0.12065 -0.3048)
			(end 0.67945 -0.3048)
			(stroke
				(width 0.1)
				(type default)
			)
			(layer "F.Fab")
		)
		(fp_line
			(start 0.67945 -0.3048)
			(end 0.67945 0.3048)
			(stroke
				(width 0.1)
				(type default)
			)
			(layer "F.Fab")
		)
		(fp_line
			(start -0.67945 -0.305054)
			(end -0.12065 -0.305054)
			(stroke
				(width 0.1)
				(type default)
			)
			(layer "F.Fab")
		)
		(fp_line
			(start -0.12065 -0.305054)
			(end -0.12065 -0.2794)
			(stroke
				(width 0.1)
				(type default)
			)
			(layer "F.Fab")
		)
		(pad "1" smd circle
			(at -0.40005 0 270)
			(size 0 0)
			(layers "F.Cu" "F.Mask" "F.Paste")
			(net "SMB_FAN2_R_SCL")
		)
		(pad "2" smd circle
			(at 0.40005 0 270)
			(size 0 0)
			(layers "F.Cu" "F.Mask" "F.Paste")
			(net "P3V3_AUX")
		)
	)
)
